# T6G (Grand Teton) — schematic netlist excerpt (pin names and nets, part order shuffled) for the footprints in the layout excerpt that follows; sources: Cadence DE-HDL packaged netlist, KiCad conversion of 04192023_DAF0TMB3IC0_F0TG_MB_C_brd_V02_OCP.brd

PC6571  Q_CAPP  390UF 2.5V 20% ALUM  pkg SMLF  page 363 : A = P0V9_CPU0_RT_2D ; B = GND
PL6510  Q_INDUCTOR  100NH/16A IND  pkg SMLF  page 365 : \1\ = SW_P12V_AUX_P0V9_RETIMER_CPU1_FLT ; \2\ = P12V_AUX
PC548_C0P0_3  Q_CAP  2.2UF 10V 10% X6S  pkg C0402  page 195 : A = PVDDCR_CPU0_P0_PVCC ; B = GND

(kicad_pcb
	(version 20260206)
	(generator "pcbnew")
	(generator_version "10.0")
	(general
		(thickness 1.6)
		(legacy_teardrops no)
	)
	(paper "A4")
	(title_block
		(title "04192023_DAF0TMB3IC0_F0TG_MB_C_brd_V02_OCP.brd")
		(comment 1 "Grand Teton / footprints 3667-3669 of 8354")
	)
	(layers
		(0 "F.Cu" signal "TOP")
		(4 "In1.Cu" signal "GND")
		(6 "In2.Cu" signal "IN1")
		(8 "In3.Cu" signal "GND1")
		(10 "In4.Cu" signal "IN2")
		(12 "In5.Cu" signal "GND2")
		(14 "In6.Cu" signal "IN3")
		(16 "In7.Cu" signal "GND3")
		(18 "In8.Cu" signal "VCC")
		(20 "In9.Cu" signal "VCC1")
		(22 "In10.Cu" signal "GND4")
		(24 "In11.Cu" signal "IN4")
		(26 "In12.Cu" signal "GND5")
		(28 "In13.Cu" signal "IN5")
		(30 "In14.Cu" signal "GND6")
		(32 "In15.Cu" signal "IN6")
		(34 "In16.Cu" signal "GND7")
		(2 "B.Cu" signal "BOTTOM")
		(9 "F.Adhes" user "F.Adhesive")
		(11 "B.Adhes" user "B.Adhesive")
		(13 "F.Paste" user "Package Geometry/Pastemask Top")
		(15 "B.Paste" user "Package Geometry/Pastemask Bottom")
		(5 "F.SilkS" user "Ref Des/Silkscreen Top")
		(7 "B.SilkS" user "Ref Des/Silkscreen Bottom")
		(1 "F.Mask" user "Board Geometry/Soldermask Top")
		(3 "B.Mask" user "Board Geometry/Soldermask Bottom")
		(17 "Dwgs.User" user "User.Drawings")
		(19 "Cmts.User" user "User.Comments")
		(21 "Eco1.User" user "User.Eco1")
		(23 "Eco2.User" user "User.Eco2")
		(25 "Edge.Cuts" user "Board Geometry/Outline")
		(27 "Margin" user)
		(31 "F.CrtYd" user "Package Geometry/Place Bound Top")
		(29 "B.CrtYd" user "Package Geometry/Place Bound Bottom")
		(35 "F.Fab" user "Ref Des/Assembly Top")
		(33 "B.Fab" user "Ref Des/Assembly Bottom")
	)
	(footprint ""
		(layer "F.Cu")
		(at 384.760978 -182.745634 90)
		(property "Reference" "PC548_C0P0_3"
			(at 0 0 90)
			(layer "F.SilkS")
			(hide yes)
			(effects
				(font
					(size 1.27 1.27)
				)
			)
		)
		(property "Value" ""
			(at 0 0 90)
			(layer "F.Fab")
			(effects
				(font
					(size 1.27 1.27)
				)
			)
		)
		(duplicate_pad_numbers_are_jumpers no)
		(fp_line
			(start 0.7874 -0.4064)
			(end 0.7874 0.4064)
			(stroke
				(width 0.1524)
				(type default)
			)
			(layer "F.SilkS")
		)
		(fp_line
			(start -0.7874 -0.4064)
			(end 0.7874 -0.4064)
			(stroke
				(width 0.1524)
				(type default)
			)
			(layer "F.SilkS")
		)
		(fp_line
			(start 0.7874 0.4064)
			(end -0.7874 0.4064)
			(stroke
				(width 0.1524)
				(type default)
			)
			(layer "F.SilkS")
		)
		(fp_line
			(start -0.7874 0.4064)
			(end -0.7874 -0.4064)
			(stroke
				(width 0.1524)
				(type default)
			)
			(layer "F.SilkS")
		)
		(fp_line
			(start -0.12065 -0.305054)
			(end -0.12065 -0.2794)
			(stroke
				(width 0.1)
				(type default)
			)
			(layer "F.Fab")
		)
		(fp_line
			(start -0.67945 -0.305054)
			(end -0.12065 -0.305054)
			(stroke
				(width 0.1)
				(type default)
			)
			(layer "F.Fab")
		)
		(fp_line
			(start 0.67945 -0.3048)
			(end 0.67945 0.3048)
			(stroke
				(width 0.1)
				(type default)
			)
			(layer "F.Fab")
		)
		(fp_line
			(start 0.12065 -0.3048)
			(end 0.67945 -0.3048)
			(stroke
				(width 0.1)
				(type default)
			)
			(layer "F.Fab")
		)
		(fp_line
			(start 0.12065 -0.2794)
			(end 0.12065 -0.3048)
			(stroke
				(width 0.1)
				(type default)
			)
			(layer "F.Fab")
		)
		(fp_line
			(start -0.12065 -0.2794)
			(end 0.12065 -0.2794)
			(stroke
				(width 0.1)
				(type default)
			)
			(layer "F.Fab")
		)
		(fp_line
			(start 0.120396 0.2794)
			(end -0.12065 0.2794)
			(stroke
				(width 0.1)
				(type default)
			)
			(layer "F.Fab")
		)
		(fp_line
			(start -0.12065 0.2794)
			(end -0.12065 0.3048)
			(stroke
				(width 0.1)
				(type default)
			)
			(layer "F.Fab")
		)
		(fp_line
			(start 0.67945 0.3048)
			(end 0.120396 0.3048)
			(stroke
				(width 0.1)
				(type default)
			)
			(layer "F.Fab")
		)
		(fp_line
			(start 0.120396 0.3048)
			(end 0.120396 0.2794)
			(stroke
				(width 0.1)
				(type default)
			)
			(layer "F.Fab")
		)
		(fp_line
			(start -0.12065 0.3048)
			(end -0.67945 0.3048)
			(stroke
				(width 0.1)
				(type default)
			)
			(layer "F.Fab")
		)
		(fp_line
			(start -0.67945 0.3048)
			(end -0.67945 -0.305054)
			(stroke
				(width 0.1)
				(type default)
			)
			(layer "F.Fab")
		)
		(pad "1" smd circle
			(at -0.40005 0 90)
			(size 0 0)
			(layers "F.Cu" "F.Mask" "F.Paste")
			(net "PVDDCR_CPU0_P0_PVCC")
		)
		(pad "2" smd circle
			(at 0.40005 0 90)
			(size 0 0)
			(layers "F.Cu" "F.Mask" "F.Paste")
			(net "GND")
		)
	)
	(footprint ""
		(layer "F.Cu")
		(at 443.859666 -380.13767 -90)
		(property "Reference" "PC6571"
			(at 4.75234 2.153666 0)
			(unlocked yes)
			(layer "F.SilkS")
			(effects
				(font
					(size 0.7874 0.5842)
					(thickness 0.1524)
				)
				(justify left)
			)
		)
		(property "Value" ""
			(at 0 0 270)
			(layer "F.Fab")
			(effects
				(font
					(size 1.27 1.27)
				)
			)
		)
		(duplicate_pad_numbers_are_jumpers no)
		(fp_line
			(start -1.988058 2.750058)
			(end 2.750058 2.750058)
			(stroke
				(width 0.1524)
				(type default)
			)
			(layer "F.SilkS")
		)
		(fp_line
			(start 2.750058 2.750058)
			(end 2.750058 0.9398)
			(stroke
				(width 0.1524)
				(type default)
			)
			(layer "F.SilkS")
		)
		(fp_line
			(start -2.750058 1.988058)
			(end -1.988058 2.750058)
			(stroke
				(width 0.1524)
				(type default)
			)
			(layer "F.SilkS")
		)
		(fp_line
			(start -2.750058 0.9398)
			(end -2.750058 1.988058)
			(stroke
				(width 0.1524)
				(type default)
			)
			(layer "F.SilkS")
		)
		(fp_line
			(start 2.750058 -0.9398)
			(end 2.750058 -2.750058)
			(stroke
				(width 0.1524)
				(type default)
			)
			(layer "F.SilkS")
		)
		(fp_line
			(start -2.750058 -1.988058)
			(end -2.750058 -0.9398)
			(stroke
				(width 0.1524)
				(type default)
			)
			(layer "F.SilkS")
		)
		(fp_line
			(start -1.988058 -2.750058)
			(end -2.750058 -1.988058)
			(stroke
				(width 0.1524)
				(type default)
			)
			(layer "F.SilkS")
		)
		(fp_line
			(start 2.750058 -2.750058)
			(end -1.988058 -2.750058)
			(stroke
				(width 0.1524)
				(type default)
			)
			(layer "F.SilkS")
		)
		(fp_line
			(start -2.750058 2.750058)
			(end 2.750058 2.750058)
			(stroke
				(width 0.1)
				(type default)
			)
			(layer "F.Fab")
		)
		(fp_line
			(start 2.750058 2.750058)
			(end 2.750058 -2.750058)
			(stroke
				(width 0.1)
				(type default)
			)
			(layer "F.Fab")
		)
		(fp_line
			(start -2.750058 -2.750058)
			(end -2.750058 2.750058)
			(stroke
				(width 0.1)
				(type default)
			)
			(layer "F.Fab")
		)
		(fp_line
			(start 2.750058 -2.750058)
			(end -2.750058 -2.750058)
			(stroke
				(width 0.1)
				(type default)
			)
			(layer "F.Fab")
		)
		(pad "1" smd rect
			(at -2.199894 0)
			(size 1.6002 3.0226)
			(layers "F.Cu" "F.Mask" "F.Paste")
			(net "P0V9_CPU0_RT_2D")
		)
		(pad "2" smd rect
			(at 2.199894 0)
			(size 1.6002 3.0226)
			(layers "F.Cu" "F.Mask" "F.Paste")
			(net "GND")
		)
	)
	(footprint ""
		(layer "F.Cu")
		(at 24.759158 -402.599906 90)
		(property "Reference" "PL6510"
			(at -3.592576 -2.153158 0)
			(unlocked yes)
			(layer "F.SilkS")
			(effects
				(font
					(size 0.7874 0.5842)
					(thickness 0.1524)
				)
				(justify left)
			)
		)
		(property "Value" ""
			(at 0 0 90)
			(layer "F.Fab")
			(effects
				(font
					(size 1.27 1.27)
				)
			)
		)
		(duplicate_pad_numbers_are_jumpers no)
		(fp_line
			(start 2.249932 -2.249932)
			(end 2.249932 -1.3843)
			(stroke
				(width 0.1524)
				(type default)
			)
			(layer "F.SilkS")
		)
		(fp_line
			(start -2.249932 -2.249932)
			(end 2.249932 -2.249932)
			(stroke
				(width 0.1524)
				(type default)
			)
			(layer "F.SilkS")
		)
		(fp_line
			(start -2.249932 -1.3843)
			(end -2.249932 -2.249932)
			(stroke
				(width 0.1524)
				(type default)
			)
			(layer "F.SilkS")
		)
		(fp_line
			(start 2.249932 1.3843)
			(end 2.249932 2.249932)
			(stroke
				(width 0.1524)
				(type default)
			)
			(layer "F.SilkS")
		)
		(fp_line
			(start 2.249932 2.249932)
			(end -2.249932 2.249932)
			(stroke
				(width 0.1524)
				(type default)
			)
			(layer "F.SilkS")
		)
		(fp_line
			(start -2.249932 2.249932)
			(end -2.249932 1.3843)
			(stroke
				(width 0.1524)
				(type default)
			)
			(layer "F.SilkS")
		)
		(fp_line
			(start 2.249932 -2.249932)
			(end 2.249932 2.249932)
			(stroke
				(width 0.1)
				(type default)
			)
			(layer "F.Fab")
		)
		(fp_line
			(start -2.249932 -2.249932)
			(end 2.249932 -2.249932)
			(stroke
				(width 0.1)
				(type default)
			)
			(layer "F.Fab")
		)
		(fp_line
			(start 2.249932 2.249932)
			(end -2.249932 2.249932)
			(stroke
				(width 0.1)
				(type default)
			)
			(layer "F.Fab")
		)
		(fp_line
			(start -2.249932 2.249932)
			(end -2.249932 -2.249932)
			(stroke
				(width 0.1)
				(type default)
			)
			(layer "F.Fab")
		)
		(pad "1" smd rect
			(at -1.82499 0 90)
			(size 1.0668 2.5146)
			(layers "F.Cu" "F.Mask" "F.Paste")
			(net "SW_P12V_AUX_P0V9_RETIMER_CPU1_FLT")
		)
		(pad "2" smd rect
			(at 1.82499 0 90)
			(size 1.0668 2.5146)
			(layers "F.Cu" "F.Mask" "F.Paste")
			(net "P12V_AUX")
		)
	)
)
